# BASEBOARD_FAB2 (Tioga Pass) — schematic netlist excerpt (pin names and nets, part order shuffled) for the footprints in the layout excerpt that follows; sources: Cadence DE-HDL packaged netlist, KiCad conversion of Wiwynn_Tioga_Pass_MB.brd

R2T7  RES  1.00K 1% CHIP  pkg 0402  page 157 : A = P3V3_STBY ; B = H_CPU0_FAST_WAKE_LVT3_N
C4P7  CAP  100UF 4V 20% X5R  pkg 0805  page 42 : A = PVCCMCP_CPU0 ; B = GND
C1T10  CAP_A  0.1UF 16V 10% X7R  pkg 0402V  page 158 : A = P3V3_STBY ; B = GND

(kicad_pcb
	(version 20260206)
	(generator "pcbnew")
	(generator_version "10.0")
	(general
		(thickness 1.6)
		(legacy_teardrops no)
	)
	(paper "A4")
	(title_block
		(title "Wiwynn_Tioga_Pass_MB.brd")
		(comment 1 "Tioga Pass / footprints 4703-4705 of 4770")
	)
	(layers
		(0 "F.Cu" signal "TOP")
		(4 "In1.Cu" signal "L2GND")
		(6 "In2.Cu" signal "L3")
		(8 "In3.Cu" signal "L4GND")
		(10 "In4.Cu" signal "L5")
		(12 "In5.Cu" signal "L6GND")
		(14 "In6.Cu" signal "L7VCC")
		(16 "In7.Cu" signal "L8VCC")
		(18 "In8.Cu" signal "L9GND")
		(20 "In9.Cu" signal "L10")
		(22 "In10.Cu" signal "L11GND")
		(24 "In11.Cu" signal "L12")
		(26 "In12.Cu" signal "L13GND")
		(2 "B.Cu" signal "BOTTOM")
		(9 "F.Adhes" user "F.Adhesive")
		(11 "B.Adhes" user "B.Adhesive")
		(13 "F.Paste" user "Package Geometry/Pastemask Top")
		(15 "B.Paste" user "Package Geometry/Pastemask Bottom")
		(5 "F.SilkS" user "Ref Des/Silkscreen Top")
		(7 "B.SilkS" user "Ref Des/Silkscreen Bottom")
		(1 "F.Mask" user "Board Geometry/Soldermask Top")
		(3 "B.Mask" user "Board Geometry/Soldermask Bottom")
		(17 "Dwgs.User" user "User.Drawings")
		(19 "Cmts.User" user "User.Comments")
		(21 "Eco1.User" user "User.Eco1")
		(23 "Eco2.User" user "User.Eco2")
		(25 "Edge.Cuts" user "Board Geometry/Outline")
		(27 "Margin" user)
		(31 "F.CrtYd" user "Package Geometry/Place Bound Top")
		(29 "B.CrtYd" user "Package Geometry/Place Bound Bottom")
		(35 "F.Fab" user "Ref Des/Assembly Top")
		(33 "B.Fab" user "Ref Des/Assembly Bottom")
	)
	(footprint ""
		(layer "B.Cu")
		(at 421.386 -14.9352 90)
		(property "Reference" "R2T7"
			(at 0 0 90)
			(layer "B.SilkS")
			(hide yes)
			(effects
				(font
					(size 1.27 1.27)
				)
				(justify mirror)
			)
		)
		(property "Value" ""
			(at 0 0 90)
			(layer "B.Fab")
			(effects
				(font
					(size 1.27 1.27)
				)
				(justify mirror)
			)
		)
		(duplicate_pad_numbers_are_jumpers no)
		(fp_poly
			(pts
				(xy 0.2794 -0.1016) (xy -0.2794 -0.1016) (xy -0.2794 0.9906) (xy 0.2794 0.9906)
			)
			(stroke
				(width 0)
				(type default)
			)
			(fill no)
			(layer "B.CrtYd")
		)
		(fp_line
			(start 0.2794 -0.1016)
			(end 0.2794 0.9906)
			(stroke
				(width 0.1)
				(type default)
			)
			(layer "B.Fab")
		)
		(fp_line
			(start -0.2794 -0.1016)
			(end 0.2794 -0.1016)
			(stroke
				(width 0.1)
				(type default)
			)
			(layer "B.Fab")
		)
		(fp_line
			(start 0.2794 0.9906)
			(end -0.2794 0.9906)
			(stroke
				(width 0.1)
				(type default)
			)
			(layer "B.Fab")
		)
		(fp_line
			(start -0.2794 0.9906)
			(end -0.2794 -0.1016)
			(stroke
				(width 0.1)
				(type default)
			)
			(layer "B.Fab")
		)
		(pad "1" smd rect
			(at 0 0 270)
			(size 0.508 0.508)
			(layers "B.Cu" "B.Mask" "B.Paste")
			(net "P3V3_STBY")
		)
		(pad "2" smd rect
			(at 0 0.889 270)
			(size 0.508 0.508)
			(layers "B.Cu" "B.Mask" "B.Paste")
			(net "H_CPU0_FAST_WAKE_LVT3_N")
		)
		(zone
			(layer "B.Cu")
			(hatch none 0.5)
			(connect_pads
				(clearance 0)
			)
			(min_thickness 0.25)
			(keepout
				(tracks allowed)
				(vias not_allowed)
				(pads allowed)
				(copperpour not_allowed)
				(footprints allowed)
			)
			(placement
				(enabled no)
				(sheetname "")
			)
			(fill
				(thermal_gap 0.5)
				(thermal_bridge_width 0.5)
				(island_removal_mode 0)
			)
			(polygon
				(pts
					(xy 421.64 -15.1892) (xy 421.64 -14.6812) (xy 422.021 -14.6812) (xy 422.021 -15.1892)
				)
			)
		)
		(zone
			(layer "B.Cu")
			(hatch none 0.5)
			(connect_pads
				(clearance 0)
			)
			(min_thickness 0.25)
			(keepout
				(tracks not_allowed)
				(vias allowed)
				(pads allowed)
				(copperpour not_allowed)
				(footprints allowed)
			)
			(placement
				(enabled no)
				(sheetname "")
			)
			(fill
				(thermal_gap 0.5)
				(thermal_bridge_width 0.5)
				(island_removal_mode 0)
			)
			(polygon
				(pts
					(xy 422.021 -15.1892) (xy 422.021 -14.6812) (xy 421.64 -14.6812) (xy 421.64 -15.1892)
				)
			)
		)
	)
	(footprint ""
		(layer "B.Cu")
		(at 276.836886 -73.51014)
		(property "Reference" "C4P7"
			(at 0 0 0)
			(layer "B.SilkS")
			(hide yes)
			(effects
				(font
					(size 1.27 1.27)
				)
				(justify mirror)
			)
		)
		(property "Value" ""
			(at 0 0 0)
			(layer "B.Fab")
			(effects
				(font
					(size 1.27 1.27)
				)
				(justify mirror)
			)
		)
		(duplicate_pad_numbers_are_jumpers no)
		(fp_poly
			(pts
				(xy 0.7239 -0.2159) (xy -0.7239 -0.2159) (xy -0.7239 1.9939) (xy 0.7239 1.9939)
			)
			(stroke
				(width 0)
				(type default)
			)
			(fill no)
			(layer "B.CrtYd")
		)
		(fp_line
			(start -0.7239 -0.2159)
			(end 0.7239 -0.2159)
			(stroke
				(width 0.1)
				(type default)
			)
			(layer "B.Fab")
		)
		(fp_line
			(start -0.7239 1.9939)
			(end -0.7239 -0.2159)
			(stroke
				(width 0.1)
				(type default)
			)
			(layer "B.Fab")
		)
		(fp_line
			(start 0.7239 -0.2159)
			(end 0.7239 1.9939)
			(stroke
				(width 0.1)
				(type default)
			)
			(layer "B.Fab")
		)
		(fp_line
			(start 0.7239 1.9939)
			(end -0.7239 1.9939)
			(stroke
				(width 0.1)
				(type default)
			)
			(layer "B.Fab")
		)
		(pad "1" smd rect
			(at 0 0 180)
			(size 1.27 1.016)
			(layers "B.Cu" "B.Mask" "B.Paste")
			(net "PVCCMCP_CPU0")
		)
		(pad "2" smd rect
			(at 0 1.778 180)
			(size 1.27 1.016)
			(layers "B.Cu" "B.Mask" "B.Paste")
			(net "GND")
		)
		(zone
			(layer "B.Cu")
			(hatch none 0.5)
			(connect_pads
				(clearance 0)
			)
			(min_thickness 0.25)
			(keepout
				(tracks not_allowed)
				(vias allowed)
				(pads allowed)
				(copperpour not_allowed)
				(footprints allowed)
			)
			(placement
				(enabled no)
				(sheetname "")
			)
			(fill
				(thermal_gap 0.5)
				(thermal_bridge_width 0.5)
				(island_removal_mode 0)
			)
			(polygon
				(pts
					(xy 277.471886 -73.00214) (xy 276.201886 -73.00214) (xy 276.201886 -72.24014) (xy 277.471886 -72.24014)
				)
			)
		)
	)
	(footprint ""
		(layer "B.Cu")
		(at 500.824246 -38.069774 -90)
		(property "Reference" "C1T10"
			(at 0 0 90)
			(layer "B.SilkS")
			(hide yes)
			(effects
				(font
					(size 1.27 1.27)
				)
				(justify mirror)
			)
		)
		(property "Value" ""
			(at 0 0 90)
			(layer "B.Fab")
			(effects
				(font
					(size 1.27 1.27)
				)
				(justify mirror)
			)
		)
		(duplicate_pad_numbers_are_jumpers no)
		(fp_poly
			(pts
				(xy -0.3048 -0.1016) (xy -0.3048 0.9906) (xy 0.3048 0.9906) (xy 0.3048 -0.1016)
			)
			(stroke
				(width 0)
				(type default)
			)
			(fill no)
			(layer "B.CrtYd")
		)
		(fp_line
			(start -0.3048 0.9906)
			(end -0.3048 -0.1016)
			(stroke
				(width 0.1)
				(type default)
			)
			(layer "B.Fab")
		)
		(fp_line
			(start 0.3048 0.9906)
			(end -0.3048 0.9906)
			(stroke
				(width 0.1)
				(type default)
			)
			(layer "B.Fab")
		)
		(fp_line
			(start -0.3048 -0.1016)
			(end 0.3048 -0.1016)
			(stroke
				(width 0.1)
				(type default)
			)
			(layer "B.Fab")
		)
		(fp_line
			(start 0.3048 -0.1016)
			(end 0.3048 0.9906)
			(stroke
				(width 0.1)
				(type default)
			)
			(layer "B.Fab")
		)
		(pad "1" smd rect
			(at 0 0 90)
			(size 0.508 0.508)
			(layers "B.Cu" "B.Mask" "B.Paste")
			(net "P3V3_STBY")
		)
		(pad "2" smd rect
			(at 0 0.889 90)
			(size 0.508 0.508)
			(layers "B.Cu" "B.Mask" "B.Paste")
			(net "GND")
		)
		(zone
			(layer "B.Cu")
			(hatch none 0.5)
			(connect_pads
				(clearance 0)
			)
			(min_thickness 0.25)
			(keepout
				(tracks not_allowed)
				(vias allowed)
				(pads allowed)
				(copperpour not_allowed)
				(footprints allowed)
			)
			(placement
				(enabled no)
				(sheetname "")
			)
			(fill
				(thermal_gap 0.5)
				(thermal_bridge_width 0.5)
				(island_removal_mode 0)
			)
			(polygon
				(pts
					(xy 500.189246 -37.815774) (xy 500.189246 -38.323774) (xy 500.570246 -38.323774) (xy 500.570246 -37.815774)
				)
			)
		)
		(zone
			(layer "B.Cu")
			(hatch none 0.5)
			(connect_pads
				(clearance 0)
			)
			(min_thickness 0.25)
			(keepout
				(tracks allowed)
				(vias not_allowed)
				(pads allowed)
				(copperpour not_allowed)
				(footprints allowed)
			)
			(placement
				(enabled no)
				(sheetname "")
			)
			(fill
				(thermal_gap 0.5)
				(thermal_bridge_width 0.5)
				(island_removal_mode 0)
			)
			(polygon
				(pts
					(xy 500.570246 -37.815774) (xy 500.570246 -38.323774) (xy 500.189246 -38.323774) (xy 500.189246 -37.815774)
				)
			)
		)
	)
)
